FILE_TYPE = CONNECTIVITY;
{Allegro Design Entry HDL 17.4-2019 S026 (4007227) 1/17/2022}
"PAGE_NUMBER" = 427;
0"NC";
1"P5E_CPU0_P3_RX_DP<7:0>";
2"P5E_CPU0_P3_RX_DP<15:8>";
3"P5E_CPU0_P3_RX_DN<15:8>";
4"P5E_CPU0_P3_RX_DN<7:0>";
5"P5E_CPU0_P3_RX_DN<15>";
6"P5E_CPU0_P3_RX_DP<14>";
7"P5E_CPU0_P3_RX_DN<14>";
8"P5E_CPU0_P3_RX_DN<12>";
9"P5E_CPU0_P3_RX_DN<8>";
10"P5E_CPU0_P3_RX_DN<9>";
11"P5E_CPU0_P3_RX_DN<10>";
12"P5E_CPU0_P3_RX_DN<0>";
13"P5E_CPU0_P3_RX_DN<1>";
14"P5E_CPU0_P3_RX_DN<6>";
15"P5E_CPU0_P3_RX_DN<7>";
16"P5E_CPU0_P3_RX_DN<2>";
17"P5E_CPU0_P3_RX_DN<11>";
18"P5E_CPU0_P3_RX_DN<5>";
19"P5E_CPU0_P3_RX_DN<3>";
20"P5E_CPU0_P3_RX_DN<4>";
21"P5E_CPU0_P3_RX_DN<13>";
22"P5E_CPU0_P3_RX_DP<15>";
23"P5E_CPU0_P3_RX_DP<6>";
24"P5E_CPU0_P3_RX_DP<0>";
25"P5E_CPU0_P3_RX_DP<1>";
26"P5E_CPU0_P3_RX_DP<2>";
27"P5E_CPU0_P3_RX_DP<3>";
28"P5E_CPU0_P3_RX_DP<7>";
29"P5E_CPU0_P3_RX_DP<12>";
30"P5E_CPU0_P3_RX_DP<8>";
31"P5E_CPU0_P3_RX_DP<9>";
32"P5E_CPU0_P3_RX_DP<10>";
33"P5E_CPU0_P3_RX_DP<11>";
34"P5E_CPU0_P3_RX_DP<5>";
35"P5E_CPU0_P3_RX_DP<13>";
36"P5E_CPU0_P3_RX_DP<4>";
%"PT5161LRS"
"6","(-7675,4375)","0","pure_quanta","I1";
;
LOCATION"U6013"
$SEC"6"
CDS_SEC"6"
PART_TYPE"SMLF"
MATERIAL"IC"
VALUE"PT5161LRS"
NEEDS_NO_SIZE"TRUE"
CDS_LMAN_SYM_OUTLINE"-350,1450,300,-1400"
CDS_LIB"pure_quanta"
PART_NUMBER"AJ051610U03";
"A_PETN7"
$PN"CC29"9;
"A_PETP7"
$PN"CA26"30;
"A_PETN6"
$PN"BT29"10;
"A_PETP6"
$PN"BP26"31;
"A_PETN5"
$PN"BJ29"11;
"A_PETP5"
$PN"BG26"32;
"A_PETN4"
$PN"BB29"17;
"A_PETP4"
$PN"AY26"33;
"A_PETN3"
$PN"AR29"8;
"A_PETP3"
$PN"AN26"29;
"A_PETN2"
$PN"AH29"21;
"A_PETP2"
$PN"AF26"35;
"A_PETN1"
$PN"AA29"7;
"A_PETP1"
$PN"W26"6;
"A_PETN0"
$PN"P29"5;
"A_PETP0"
$PN"M26"22;
%"TAP"
"1","(-6450,4125)","0","standard","I10";
;
CDS_LIB"standard"
BODY_TYPE"PLUMBING"
HDL_TAP"TRUE";
"B \NAC \NWC"3;
"S \NAC"
BN"11"17;
%"TAP"
"1","(-6450,4475)","0","standard","I11";
;
CDS_LIB"standard"
BODY_TYPE"PLUMBING"
HDL_TAP"TRUE";
"B \NAC \NWC"3;
"S \NAC"
BN"12"8;
%"TAP"
"1","(-6650,4925)","0","standard","I12";
;
CDS_LIB"standard"
BODY_TYPE"PLUMBING"
HDL_TAP"TRUE";
"B \NAC \NWC"2;
"S \NAC"
BN"13"35;
%"TAP"
"1","(-6650,5275)","0","standard","I13";
;
CDS_LIB"standard"
BODY_TYPE"PLUMBING"
HDL_TAP"TRUE";
"B \NAC \NWC"2;
"S \NAC"
BN"14"6;
%"TAP"
"1","(-6450,4825)","0","standard","I14";
;
CDS_LIB"standard"
BODY_TYPE"PLUMBING"
HDL_TAP"TRUE";
"B \NAC \NWC"3;
"S \NAC"
BN"13"21;
%"TAP"
"1","(-6450,5175)","0","standard","I15";
;
CDS_LIB"standard"
BODY_TYPE"PLUMBING"
HDL_TAP"TRUE";
"B \NAC \NWC"3;
"S \NAC"
BN"14"7;
%"TAP"
"1","(-6450,5525)","0","standard","I16";
;
CDS_LIB"standard"
BODY_TYPE"PLUMBING"
HDL_TAP"TRUE";
"B \NAC \NWC"3;
"S \NAC"
BN"15"5;
%"TAP"
"1","(-6650,5625)","0","standard","I17";
;
CDS_LIB"standard"
BODY_TYPE"PLUMBING"
HDL_TAP"TRUE";
"B \NAC \NWC"2;
"S \NAC"
BN"15"22;
%"TAP"
"1","(-6650,3175)","0","standard","I2";
;
CDS_LIB"standard"
BODY_TYPE"PLUMBING"
HDL_TAP"TRUE";
"B \NAC \NWC"2;
"S \NAC"
BN"8"30;
%"TAP"
"1","(-2150,3125)","0","standard","I20";
;
CDS_LIB"standard"
BODY_TYPE"PLUMBING"
HDL_TAP"TRUE";
"B \NAC \NWC"1;
"S \NAC"
BN"0"24;
%"TAP"
"1","(-1950,3025)","0","standard","I21";
;
CDS_LIB"standard"
BODY_TYPE"PLUMBING"
HDL_TAP"TRUE";
"B \NAC \NWC"4;
"S \NAC"
BN"0"12;
%"TAP"
"1","(-1950,3375)","0","standard","I22";
;
CDS_LIB"standard"
BODY_TYPE"PLUMBING"
HDL_TAP"TRUE";
"B \NAC \NWC"4;
"S \NAC"
BN"1"13;
%"TAP"
"1","(-2150,3475)","0","standard","I23";
;
CDS_LIB"standard"
BODY_TYPE"PLUMBING"
HDL_TAP"TRUE";
"B \NAC \NWC"1;
"S \NAC"
BN"1"25;
%"TAP"
"1","(-2150,3825)","0","standard","I24";
;
CDS_LIB"standard"
BODY_TYPE"PLUMBING"
HDL_TAP"TRUE";
"B \NAC \NWC"1;
"S \NAC"
BN"2"26;
%"TAP"
"1","(-1950,3725)","0","standard","I25";
;
CDS_LIB"standard"
BODY_TYPE"PLUMBING"
HDL_TAP"TRUE";
"B \NAC \NWC"4;
"S \NAC"
BN"2"16;
%"TAP"
"1","(-2150,4175)","0","standard","I26";
;
CDS_LIB"standard"
BODY_TYPE"PLUMBING"
HDL_TAP"TRUE";
"B \NAC \NWC"1;
"S \NAC"
BN"3"27;
%"TAP"
"1","(-1950,4075)","0","standard","I27";
;
CDS_LIB"standard"
BODY_TYPE"PLUMBING"
HDL_TAP"TRUE";
"B \NAC \NWC"4;
"S \NAC"
BN"3"19;
%"TAP"
"1","(-1950,4425)","0","standard","I28";
;
CDS_LIB"standard"
BODY_TYPE"PLUMBING"
HDL_TAP"TRUE";
"B \NAC \NWC"4;
"S \NAC"
BN"4"20;
%"TAP"
"1","(-2150,4525)","0","standard","I29";
;
CDS_LIB"standard"
BODY_TYPE"PLUMBING"
HDL_TAP"TRUE";
"B \NAC \NWC"1;
"S \NAC"
BN"4"36;
%"TAP"
"1","(-6650,3525)","0","standard","I3";
;
CDS_LIB"standard"
BODY_TYPE"PLUMBING"
HDL_TAP"TRUE";
"B \NAC \NWC"2;
"S \NAC"
BN"9"31;
%"TAP"
"1","(-2150,4875)","0","standard","I30";
;
CDS_LIB"standard"
BODY_TYPE"PLUMBING"
HDL_TAP"TRUE";
"B \NAC \NWC"1;
"S \NAC"
BN"5"34;
%"TAP"
"1","(-1950,4775)","0","standard","I31";
;
CDS_LIB"standard"
BODY_TYPE"PLUMBING"
HDL_TAP"TRUE";
"B \NAC \NWC"4;
"S \NAC"
BN"5"18;
%"TAP"
"1","(-2150,5225)","0","standard","I32";
;
CDS_LIB"standard"
BODY_TYPE"PLUMBING"
HDL_TAP"TRUE";
"B \NAC \NWC"1;
"S \NAC"
BN"6"23;
%"TAP"
"1","(-1950,5125)","0","standard","I33";
;
CDS_LIB"standard"
BODY_TYPE"PLUMBING"
HDL_TAP"TRUE";
"B \NAC \NWC"4;
"S \NAC"
BN"6"14;
%"TAP"
"1","(-1950,5475)","0","standard","I34";
;
CDS_LIB"standard"
BODY_TYPE"PLUMBING"
HDL_TAP"TRUE";
"B \NAC \NWC"4;
"S \NAC"
BN"7"15;
%"TAP"
"1","(-2150,5575)","0","standard","I35";
;
CDS_LIB"standard"
BODY_TYPE"PLUMBING"
HDL_TAP"TRUE";
"B \NAC \NWC"1;
"S \NAC"
BN"7"28;
%"PT5161LRS"
"7","(-3175,4325)","0","pure_quanta","I38";
;
LOCATION"U6013"
$SEC"7"
CDS_SEC"7"
MATERIAL"IC"
VALUE"PT5161LRS"
PART_TYPE"SMLF"
CDS_LIB"pure_quanta"
CDS_LMAN_SYM_OUTLINE"-350,1450,300,-1400"
NEEDS_NO_SIZE"TRUE"
PART_NUMBER"AJ051610U03";
"A_PETN15"
$PN"EW29"12;
"A_PETP15"
$PN"EU26"24;
"A_PETN14"
$PN"EM29"13;
"A_PETP14"
$PN"EK26"25;
"A_PETN13"
$PN"EE29"16;
"A_PETP13"
$PN"EC26"26;
"A_PETN12"
$PN"DV29"19;
"A_PETP12"
$PN"DT26"27;
"A_PETN11"
$PN"DL29"20;
"A_PETP11"
$PN"DJ26"36;
"A_PETN10"
$PN"DD29"18;
"A_PETP10"
$PN"DB26"34;
"A_PETN9"
$PN"CU29"14;
"A_PETP9"
$PN"CR26"23;
"A_PETN8"
$PN"CK29"15;
"A_PETP8"
$PN"CH26"28;
%"TAP"
"1","(-6450,3075)","0","standard","I4";
;
CDS_LIB"standard"
BODY_TYPE"PLUMBING"
HDL_TAP"TRUE";
"B \NAC \NWC"3;
"S \NAC"
BN"8"9;
%"TAP"
"1","(-6450,3425)","0","standard","I5";
;
CDS_LIB"standard"
BODY_TYPE"PLUMBING"
HDL_TAP"TRUE";
"B \NAC \NWC"3;
"S \NAC"
BN"9"10;
%"TAP"
"1","(-6650,3875)","0","standard","I6";
;
CDS_LIB"standard"
BODY_TYPE"PLUMBING"
HDL_TAP"TRUE";
"B \NAC \NWC"2;
"S \NAC"
BN"10"32;
%"TAP"
"1","(-6650,4225)","0","standard","I7";
;
CDS_LIB"standard"
BODY_TYPE"PLUMBING"
HDL_TAP"TRUE";
"B \NAC \NWC"2;
"S \NAC"
BN"11"33;
%"TAP"
"1","(-6650,4575)","0","standard","I8";
;
CDS_LIB"standard"
BODY_TYPE"PLUMBING"
HDL_TAP"TRUE";
"B \NAC \NWC"2;
"S \NAC"
BN"12"29;
%"TAP"
"1","(-6450,3775)","0","standard","I9";
;
CDS_LIB"standard"
BODY_TYPE"PLUMBING"
HDL_TAP"TRUE";
"B \NAC \NWC"3;
"S \NAC"
BN"10"11;
END.
